#ISCELL
  mstr_misc dns *
  *
#ISCELL
  pure_quanta quanta_title_block_c *
  *
#ISCELL
  pure_quanta_power universal_gnd *
  page194_i1
#ISCELL
  standard offpage *
  page194_i10
#ISCELL
  pure_quanta_power universal_gnd *
  page194_i11
#CELL
  pure_quanta q_cap *
  page194_i12
#CELL
  pure_quanta q_res *
  page194_i13
#ISCELL
  pure_quanta_power vcc_core *
  page194_i14
#ISCELL
  pure_quanta_power universal_gnd *
  page194_i15
#CELL
  pure_quanta q_cap *
  page194_i16
#ISCELL
  pure_quanta_power universal_gnd *
  page194_i17
#CELL
  pure_quanta q_res *
  page194_i18
#ISCELL
  standard offpage *
  page194_i19
#CELL
  pure_quanta q_cap *
  page194_i2
#ISCELL
  standard offpage *
  page194_i20
#CELL
  pure_quanta isl99390frztr5935 *
  page194_i21
#ISCELL
  pure_quanta_power universal_gnd *
  page194_i22
#CELL
  pure_quanta q_cap *
  page194_i23
#ISCELL
  pure_quanta_power universal_gnd *
  page194_i24
#ISCELL
  standard offpage *
  page194_i25
#ISCELL
  standard offpage *
  page194_i26
#CELL
  pure_quanta q_cap *
  page194_i27
#ISCELL
  pure_quanta_power universal_gnd *
  page194_i28
#CELL
  pure_quanta q_res *
  page194_i29
#ISCELL
  pure_quanta_power universal_gnd *
  page194_i3
#ISCELL
  pure_quanta_power universal_gnd *
  page194_i30
#CELL
  pure_quanta q_cap *
  page194_i31
#ISCELL
  pure_quanta_power vcc_core *
  page194_i32
#CELL
  pure_quanta q_cap *
  page194_i33
#ISCELL
  pure_quanta_power universal_gnd *
  page194_i34
#CELL
  pure_quanta q_res *
  page194_i35
#CELL
  pure_quanta q_res *
  page194_i36
#CELL
  pure_quanta q_cap *
  page194_i37
#CELL
  pure_quanta q_res *
  page194_i38
#ISCELL
  standard offpage *
  page194_i39
#CELL
  pure_quanta q_res *
  page194_i4
#CELL
  pure_quanta q_cap *
  page194_i40
#CELL
  pure_quanta q_cap *
  page194_i41
#CELL
  pure_quanta q_cap *
  page194_i42
#ISCELL
  pure_quanta_power universal_gnd *
  page194_i43
#CELL
  pure_quanta q_res *
  page194_i44
#CELL
  pure_quanta q_cap *
  page194_i45
#ISCELL
  pure_quanta_power universal_gnd *
  page194_i46
#CELL
  pure_quanta q_cap *
  page194_i47
#ISCELL
  pure_quanta_power vcc_core *
  page194_i48
#CELL
  pure_quanta q_res *
  page194_i49
#ISCELL
  standard offpage *
  page194_i5
#CELL
  pure_quanta q_inductor4p_14 *
  page194_i50
#ISCELL
  pure_quanta_power universal_gnd *
  page194_i51
#CELL
  pure_quanta q_res *
  page194_i52
#CELL
  pure_quanta q_cap *
  page194_i53
#CELL
  pure_quanta q_cap *
  page194_i54
#CELL
  pure_quanta q_cap *
  page194_i55
#ISCELL
  standard offpage *
  page194_i56
#CELL
  pure_quanta q_cap *
  page194_i57
#ISCELL
  pure_quanta_power universal_gnd *
  page194_i58
#CELL
  pure_quanta q_cap *
  page194_i59
#ISCELL
  pure_quanta_power universal_gnd *
  page194_i6
#CELL
  pure_quanta q_cap *
  page194_i60
#ISCELL
  pure_quanta_power vcc_core *
  page194_i61
#CELL
  pure_quanta q_inductor4p_14 *
  page194_i62
#ISCELL
  standard offpage *
  page194_i63
#CELL
  pure_quanta q_cap *
  page194_i64
#CELL
  pure_quanta q_cap *
  page194_i65
#ISCELL
  pure_quanta_power universal_gnd *
  page194_i66
#CELL
  pure_quanta q_cap *
  page194_i67
#ISCELL
  pure_quanta_power vcc_core *
  page194_i68
#ISCELL
  pure_quanta_power universal_gnd *
  page194_i69
#CELL
  pure_quanta q_cap *
  page194_i7
#CELL
  pure_quanta q_cap *
  page194_i70
#ISCELL
  pure_quanta_power vcc_core *
  page194_i71
#CELL
  pure_quanta isl99390frztr5935 *
  page194_i72
#ISCELL
  standard offpage *
  page194_i8
#ISCELL
  standard offpage *
  page194_i9
